(kicad_pcb
	(version 20241229)
	(generator "pcbnew")
	(generator_version "9.0")
	(general
		(thickness 1.62)
		(legacy_teardrops no)
	)
	(paper "A3")
	(title_block
		(title "COM Express 7 Baseboard")
		(date "2025-02-04")
		(rev "1.1.2")
		(company "Antmicro Ltd")
		(comment 1 "www.antmicro.com")
		(comment 9 "footprint 27 of 802 (U37), pads 1-41 of 50")
	)
	(layers
		(0 "F.Cu" signal)
		(4 "In1.Cu" signal)
		(6 "In2.Cu" signal)
		(8 "In3.Cu" signal)
		(10 "In4.Cu" signal)
		(12 "In5.Cu" signal)
		(14 "In6.Cu" signal)
		(2 "B.Cu" signal)
		(9 "F.Adhes" user "F.Adhesive")
		(11 "B.Adhes" user "B.Adhesive")
		(13 "F.Paste" user)
		(15 "B.Paste" user)
		(5 "F.SilkS" user "F.Silkscreen")
		(7 "B.SilkS" user "B.Silkscreen")
		(1 "F.Mask" user)
		(3 "B.Mask" user)
		(17 "Dwgs.User" user "User.Drawings")
		(19 "Cmts.User" user "User.Comments")
		(21 "Eco1.User" user "User.Eco1")
		(23 "Eco2.User" user "User.Eco2")
		(25 "Edge.Cuts" user)
		(27 "Margin" user)
		(31 "F.CrtYd" user "F.Courtyard")
		(29 "B.CrtYd" user "B.Courtyard")
		(35 "F.Fab" user)
		(33 "B.Fab" user)
	)
	(footprint "antmicro-footprints:VFQFPN-40-1EP_5x5mm_P0.4mm_EP3.5x3.5mm"
		(layer "F.Cu")
		(at 215.678 128.725 -90)
		(descr "UQFN, 40 Pin")
		(tags "UQFN NoLead")
		(property "Reference" "U37"
			(at -3.015 -1.022 180)
			(layer "F.SilkS")
			(effects
				(font
					(size 0.7 0.7)
					(thickness 0.15)
				)
				(justify right bottom)
			)
		)
		(property "Value" "9DBL0651CKILF"
			(at 0 3.9 90)
			(layer "F.Fab")
			(effects
				(font
					(size 0.7 0.7)
					(thickness 0.15)
				)
				(justify right bottom)
			)
		)
		(property "Datasheet" "https://eu.mouser.com/datasheet/2/698/REN_9DBL02x2_9DBL04x2_9DBL06x1_9DBL08x1C_DST_20221-3075841.pdf"
			(at 0 0 270)
			(layer "F.Fab")
			(hide yes)
			(effects
				(font
					(size 1.27 1.27)
					(thickness 0.15)
				)
			)
		)
		(property "Author" "Antmicro"
			(at 86.953 344.403 0)
			(layer "F.Fab")
			(hide yes)
			(effects
				(font
					(size 1 1)
					(thickness 0.15)
				)
			)
		)
		(property "License" "Apache-2.0"
			(at 86.953 344.403 0)
			(layer "F.Fab")
			(hide yes)
			(effects
				(font
					(size 1 1)
					(thickness 0.15)
				)
			)
		)
		(property "MPN" "9DBL0651CKILF"
			(at 86.953 344.403 0)
			(layer "F.Fab")
			(hide yes)
			(effects
				(font
					(size 1 1)
					(thickness 0.15)
				)
			)
		)
		(property "Manufacturer" "Renesas"
			(at 86.953 344.403 0)
			(layer "F.Fab")
			(hide yes)
			(effects
				(font
					(size 1 1)
					(thickness 0.15)
				)
			)
		)
		(sheetname "PCIe misc")
		(sheetfile "pcie_misc.kicad_sch")
		(attr smd)
		(pad "" smd roundrect
			(at -1.1 -1.1 270)
			(size 0.8 0.8)
			(layers "F.Paste")
			(roundrect_rratio 0.245098)
			(teardrops
				(best_length_ratio 0.2)
				(max_length 1)
				(best_width_ratio 0.9)
				(max_width 2)
				(curved_edges yes)
				(filter_ratio 0.9)
				(enabled yes)
				(allow_two_segments yes)
				(prefer_zone_connections yes)
			)
		)
		(pad "" smd roundrect
			(at -1.1 0 270)
			(size 0.8 0.8)
			(layers "F.Paste")
			(roundrect_rratio 0.245098)
			(teardrops
				(best_length_ratio 0.2)
				(max_length 1)
				(best_width_ratio 0.9)
				(max_width 2)
				(curved_edges yes)
				(filter_ratio 0.9)
				(enabled yes)
				(allow_two_segments yes)
				(prefer_zone_connections yes)
			)
		)
		(pad "" smd roundrect
			(at -1.1 1.1 270)
			(size 0.8 0.8)
			(layers "F.Paste")
			(roundrect_rratio 0.245098)
			(teardrops
				(best_length_ratio 0.2)
				(max_length 1)
				(best_width_ratio 0.9)
				(max_width 2)
				(curved_edges yes)
				(filter_ratio 0.9)
				(enabled yes)
				(allow_two_segments yes)
				(prefer_zone_connections yes)
			)
		)
		(pad "" smd roundrect
			(at 0 -1.1 270)
			(size 0.8 0.8)
			(layers "F.Paste")
			(roundrect_rratio 0.245098)
			(teardrops
				(best_length_ratio 0.2)
				(max_length 1)
				(best_width_ratio 0.9)
				(max_width 2)
				(curved_edges yes)
				(filter_ratio 0.9)
				(enabled yes)
				(allow_two_segments yes)
				(prefer_zone_connections yes)
			)
		)
		(pad "" smd roundrect
			(at 0 0 270)
			(size 0.8 0.8)
			(layers "F.Paste")
			(roundrect_rratio 0.245098)
			(teardrops
				(best_length_ratio 0.2)
				(max_length 1)
				(best_width_ratio 0.9)
				(max_width 2)
				(curved_edges yes)
				(filter_ratio 0.9)
				(enabled yes)
				(allow_two_segments yes)
				(prefer_zone_connections yes)
			)
		)
		(pad "" smd roundrect
			(at 0 1.1 270)
			(size 0.8 0.8)
			(layers "F.Paste")
			(roundrect_rratio 0.245098)
			(teardrops
				(best_length_ratio 0.2)
				(max_length 1)
				(best_width_ratio 0.9)
				(max_width 2)
				(curved_edges yes)
				(filter_ratio 0.9)
				(enabled yes)
				(allow_two_segments yes)
				(prefer_zone_connections yes)
			)
		)
		(pad "" smd roundrect
			(at 1.1 -1.1 270)
			(size 0.8 0.8)
			(layers "F.Paste")
			(roundrect_rratio 0.245098)
			(teardrops
				(best_length_ratio 0.2)
				(max_length 1)
				(best_width_ratio 0.9)
				(max_width 2)
				(curved_edges yes)
				(filter_ratio 0.9)
				(enabled yes)
				(allow_two_segments yes)
				(prefer_zone_connections yes)
			)
		)
		(pad "" smd roundrect
			(at 1.1 0 270)
			(size 0.8 0.8)
			(layers "F.Paste")
			(roundrect_rratio 0.245098)
			(teardrops
				(best_length_ratio 0.2)
				(max_length 1)
				(best_width_ratio 0.9)
				(max_width 2)
				(curved_edges yes)
				(filter_ratio 0.9)
				(enabled yes)
				(allow_two_segments yes)
				(prefer_zone_connections yes)
			)
		)
		(pad "" smd roundrect
			(at 1.1 1.1 270)
			(size 0.8 0.8)
			(layers "F.Paste")
			(roundrect_rratio 0.245098)
			(teardrops
				(best_length_ratio 0.2)
				(max_length 1)
				(best_width_ratio 0.9)
				(max_width 2)
				(curved_edges yes)
				(filter_ratio 0.9)
				(enabled yes)
				(allow_two_segments yes)
				(prefer_zone_connections yes)
			)
		)
		(pad "1" smd roundrect
			(at -2.476 -1.801 270)
			(size 0.75 0.2)
			(layers "F.Cu" "F.Mask" "F.Paste")
			(roundrect_rratio 0.25)
			(net 711 "Net-(U37-SADR_{TRI})")
			(pinfunction "SADR_{TRI}")
			(pintype "input")
			(teardrops
				(best_length_ratio 0.2)
				(max_length 1)
				(best_width_ratio 0.9)
				(max_width 2)
				(curved_edges yes)
				(filter_ratio 0.9)
				(enabled yes)
				(allow_two_segments yes)
				(prefer_zone_connections yes)
			)
		)
		(pad "2" smd roundrect
			(at -2.476 -1.401 270)
			(size 0.75 0.2)
			(layers "F.Cu" "F.Mask" "F.Paste")
			(roundrect_rratio 0.25)
			(net 607 "Net-(U37-~{HIBW_BYPM_LOBW})")
			(pinfunction "~{HIBW_BYPM_LOBW}")
			(pintype "input")
			(teardrops
				(best_length_ratio 0.2)
				(max_length 1)
				(best_width_ratio 0.9)
				(max_width 2)
				(curved_edges yes)
				(filter_ratio 0.9)
				(enabled yes)
				(allow_two_segments yes)
				(prefer_zone_connections yes)
			)
		)
		(pad "3" smd roundrect
			(at -2.476 -1 270)
			(size 0.75 0.2)
			(layers "F.Cu" "F.Mask" "F.Paste")
			(roundrect_rratio 0.25)
			(net 786 "unconnected-(U37-FB_DNC+-Pad3)")
			(pinfunction "FB_DNC+")
			(pintype "no_connect")
			(teardrops
				(best_length_ratio 0.2)
				(max_length 1)
				(best_width_ratio 0.9)
				(max_width 2)
				(curved_edges yes)
				(filter_ratio 0.9)
				(enabled yes)
				(allow_two_segments yes)
				(prefer_zone_connections yes)
			)
		)
		(pad "4" smd roundrect
			(at -2.476 -0.6 270)
			(size 0.75 0.2)
			(layers "F.Cu" "F.Mask" "F.Paste")
			(roundrect_rratio 0.25)
			(net 787 "unconnected-(U37-FB_DNC--Pad4)")
			(pinfunction "FB_DNC-")
			(pintype "no_connect")
			(teardrops
				(best_length_ratio 0.2)
				(max_length 1)
				(best_width_ratio 0.9)
				(max_width 2)
				(curved_edges yes)
				(filter_ratio 0.9)
				(enabled yes)
				(allow_two_segments yes)
				(prefer_zone_connections yes)
			)
		)
		(pad "5" smd roundrect
			(at -2.476 -0.202 270)
			(size 0.75 0.2)
			(layers "F.Cu" "F.Mask" "F.Paste")
			(roundrect_rratio 0.25)
			(net 2 "+3V3")
			(pinfunction "VDDR")
			(pintype "power_in")
			(teardrops
				(best_length_ratio 0.2)
				(max_length 1)
				(best_width_ratio 0.9)
				(max_width 2)
				(curved_edges yes)
				(filter_ratio 0.9)
				(enabled yes)
				(allow_two_segments yes)
				(prefer_zone_connections yes)
			)
		)
		(pad "6" smd roundrect
			(at -2.476 0.2 270)
			(size 0.75 0.2)
			(layers "F.Cu" "F.Mask" "F.Paste")
			(roundrect_rratio 0.25)
			(net 336 "/Com Express 7 Interfaces/PCIE_{REF}.CK+")
			(pinfunction "CLK_IN+")
			(pintype "input")
			(teardrops
				(best_length_ratio 0.2)
				(max_length 1)
				(best_width_ratio 0.9)
				(max_width 2)
				(curved_edges yes)
				(filter_ratio 0.9)
				(enabled yes)
				(allow_two_segments yes)
				(prefer_zone_connections yes)
			)
		)
		(pad "7" smd roundrect
			(at -2.476 0.598 270)
			(size 0.75 0.2)
			(layers "F.Cu" "F.Mask" "F.Paste")
			(roundrect_rratio 0.25)
			(net 337 "/Com Express 7 Interfaces/PCIE_{REF}.CK-")
			(pinfunction "CLK_IN-")
			(pintype "input")
			(teardrops
				(best_length_ratio 0.2)
				(max_length 1)
				(best_width_ratio 0.9)
				(max_width 2)
				(curved_edges yes)
				(filter_ratio 0.9)
				(enabled yes)
				(allow_two_segments yes)
				(prefer_zone_connections yes)
			)
		)
		(pad "8" smd roundrect
			(at -2.476 0.998 270)
			(size 0.75 0.2)
			(layers "F.Cu" "F.Mask" "F.Paste")
			(roundrect_rratio 0.25)
			(net 1 "GND")
			(pinfunction "GNDDIG")
			(pintype "power_in")
			(teardrops
				(best_length_ratio 0.2)
				(max_length 1)
				(best_width_ratio 0.9)
				(max_width 2)
				(curved_edges yes)
				(filter_ratio 0.9)
				(enabled no)
				(allow_two_segments yes)
				(prefer_zone_connections yes)
			)
		)
		(pad "9" smd roundrect
			(at -2.476 1.398 270)
			(size 0.75 0.2)
			(layers "F.Cu" "F.Mask" "F.Paste")
			(roundrect_rratio 0.25)
			(net 709 "Net-(U37-SCLK)")
			(pinfunction "SCLK")
			(pintype "input")
			(teardrops
				(best_length_ratio 0.2)
				(max_length 1)
				(best_width_ratio 0.9)
				(max_width 2)
				(curved_edges yes)
				(filter_ratio 0.9)
				(enabled yes)
				(allow_two_segments yes)
				(prefer_zone_connections yes)
			)
		)
		(pad "10" smd roundrect
			(at -2.476 1.8 270)
			(size 0.75 0.2)
			(layers "F.Cu" "F.Mask" "F.Paste")
			(roundrect_rratio 0.25)
			(net 710 "Net-(U37-SDAT)")
			(pinfunction "SDAT")
			(pintype "bidirectional")
			(teardrops
				(best_length_ratio 0.2)
				(max_length 1)
				(best_width_ratio 0.9)
				(max_width 2)
				(curved_edges yes)
				(filter_ratio 0.9)
				(enabled yes)
				(allow_two_segments yes)
				(prefer_zone_connections yes)
			)
		)
		(pad "11" smd roundrect
			(at -1.801 2.475 270)
			(size 0.2 0.75)
			(layers "F.Cu" "F.Mask" "F.Paste")
			(roundrect_rratio 0.25)
			(net 2 "+3V3")
			(pinfunction "VDDDIG3V3")
			(pintype "power_in")
			(teardrops
				(best_length_ratio 0.2)
				(max_length 1)
				(best_width_ratio 0.9)
				(max_width 2)
				(curved_edges yes)
				(filter_ratio 0.9)
				(enabled yes)
				(allow_two_segments yes)
				(prefer_zone_connections yes)
			)
		)
		(pad "12" smd roundrect
			(at -1.401 2.475 270)
			(size 0.2 0.75)
			(layers "F.Cu" "F.Mask" "F.Paste")
			(roundrect_rratio 0.25)
			(net 2 "+3V3")
			(pinfunction "VDDIO")
			(pintype "power_in")
			(teardrops
				(best_length_ratio 0.2)
				(max_length 1)
				(best_width_ratio 0.9)
				(max_width 2)
				(curved_edges yes)
				(filter_ratio 0.9)
				(enabled yes)
				(allow_two_segments yes)
				(prefer_zone_connections yes)
			)
		)
		(pad "13" smd roundrect
			(at -1 2.475 270)
			(size 0.2 0.75)
			(layers "F.Cu" "F.Mask" "F.Paste")
			(roundrect_rratio 0.25)
			(net 602 "Net-(U37-~{OE0})")
			(pinfunction "~{OE0}")
			(pintype "input")
			(teardrops
				(best_length_ratio 0.2)
				(max_length 1)
				(best_width_ratio 0.9)
				(max_width 2)
				(curved_edges yes)
				(filter_ratio 0.9)
				(enabled yes)
				(allow_two_segments yes)
				(prefer_zone_connections yes)
			)
		)
		(pad "14" smd roundrect
			(at -0.6 2.475 270)
			(size 0.2 0.75)
			(layers "F.Cu" "F.Mask" "F.Paste")
			(roundrect_rratio 0.25)
			(net 611 "/PCIe misc/DIF0+")
			(pinfunction "DIF0+")
			(pintype "output")
			(teardrops
				(best_length_ratio 0.2)
				(max_length 1)
				(best_width_ratio 0.9)
				(max_width 2)
				(curved_edges yes)
				(filter_ratio 0.9)
				(enabled yes)
				(allow_two_segments yes)
				(prefer_zone_connections yes)
			)
		)
		(pad "15" smd roundrect
			(at -0.202 2.475 270)
			(size 0.2 0.75)
			(layers "F.Cu" "F.Mask" "F.Paste")
			(roundrect_rratio 0.25)
			(net 612 "/PCIe misc/DIF0-")
			(pinfunction "DIF0-")
			(pintype "output")
			(teardrops
				(best_length_ratio 0.2)
				(max_length 1)
				(best_width_ratio 0.9)
				(max_width 2)
				(curved_edges yes)
				(filter_ratio 0.9)
				(enabled yes)
				(allow_two_segments yes)
				(prefer_zone_connections yes)
			)
		)
		(pad "16" smd roundrect
			(at 0.2 2.475 270)
			(size 0.2 0.75)
			(layers "F.Cu" "F.Mask" "F.Paste")
			(roundrect_rratio 0.25)
			(net 2 "+3V3")
			(pinfunction "VDD3V3")
			(pintype "power_in")
			(teardrops
				(best_length_ratio 0.2)
				(max_length 1)
				(best_width_ratio 0.9)
				(max_width 2)
				(curved_edges yes)
				(filter_ratio 0.9)
				(enabled yes)
				(allow_two_segments yes)
				(prefer_zone_connections yes)
			)
		)
		(pad "17" smd roundrect
			(at 0.598 2.475 270)
			(size 0.2 0.75)
			(layers "F.Cu" "F.Mask" "F.Paste")
			(roundrect_rratio 0.25)
			(net 2 "+3V3")
			(pinfunction "VDDIO")
			(pintype "passive")
			(teardrops
				(best_length_ratio 0.2)
				(max_length 1)
				(best_width_ratio 0.9)
				(max_width 2)
				(curved_edges yes)
				(filter_ratio 0.9)
				(enabled yes)
				(allow_two_segments yes)
				(prefer_zone_connections yes)
			)
		)
		(pad "18" smd roundrect
			(at 0.998 2.475 270)
			(size 0.2 0.75)
			(layers "F.Cu" "F.Mask" "F.Paste")
			(roundrect_rratio 0.25)
			(net 613 "/PCIe misc/DIF1+")
			(pinfunction "DIF1+")
			(pintype "output")
			(teardrops
				(best_length_ratio 0.2)
				(max_length 1)
				(best_width_ratio 0.9)
				(max_width 2)
				(curved_edges yes)
				(filter_ratio 0.9)
				(enabled yes)
				(allow_two_segments yes)
				(prefer_zone_connections yes)
			)
		)
		(pad "19" smd roundrect
			(at 1.398 2.475 270)
			(size 0.2 0.75)
			(layers "F.Cu" "F.Mask" "F.Paste")
			(roundrect_rratio 0.25)
			(net 614 "/PCIe misc/DIF1-")
			(pinfunction "DIF1-")
			(pintype "output")
			(teardrops
				(best_length_ratio 0.2)
				(max_length 1)
				(best_width_ratio 0.9)
				(max_width 2)
				(curved_edges yes)
				(filter_ratio 0.9)
				(enabled yes)
				(allow_two_segments yes)
				(prefer_zone_connections yes)
			)
		)
		(pad "20" smd roundrect
			(at 1.8 2.475 270)
			(size 0.2 0.75)
			(layers "F.Cu" "F.Mask" "F.Paste")
			(roundrect_rratio 0.25)
			(net 788 "unconnected-(U37-NC-Pad20)")
			(pinfunction "NC")
			(pintype "no_connect")
			(teardrops
				(best_length_ratio 0.2)
				(max_length 1)
				(best_width_ratio 0.9)
				(max_width 2)
				(curved_edges yes)
				(filter_ratio 0.9)
				(enabled yes)
				(allow_two_segments yes)
				(prefer_zone_connections yes)
			)
		)
		(pad "21" smd roundrect
			(at 2.475 1.8 270)
			(size 0.75 0.2)
			(layers "F.Cu" "F.Mask" "F.Paste")
			(roundrect_rratio 0.25)
			(net 603 "Net-(U37-~{OE1})")
			(pinfunction "~{OE1}")
			(pintype "input")
			(teardrops
				(best_length_ratio 0.2)
				(max_length 1)
				(best_width_ratio 0.9)
				(max_width 2)
				(curved_edges yes)
				(filter_ratio 0.9)
				(enabled yes)
				(allow_two_segments yes)
				(prefer_zone_connections yes)
			)
		)
		(pad "22" smd roundrect
			(at 2.475 1.398 270)
			(size 0.75 0.2)
			(layers "F.Cu" "F.Mask" "F.Paste")
			(roundrect_rratio 0.25)
			(net 615 "/PCIe misc/DIF2+")
			(pinfunction "DIF2+")
			(pintype "output")
			(teardrops
				(best_length_ratio 0.2)
				(max_length 1)
				(best_width_ratio 0.9)
				(max_width 2)
				(curved_edges yes)
				(filter_ratio 0.9)
				(enabled yes)
				(allow_two_segments yes)
				(prefer_zone_connections yes)
			)
		)
		(pad "23" smd roundrect
			(at 2.475 0.998 270)
			(size 0.75 0.2)
			(layers "F.Cu" "F.Mask" "F.Paste")
			(roundrect_rratio 0.25)
			(net 616 "/PCIe misc/DIF2-")
			(pinfunction "DIF2-")
			(pintype "output")
			(teardrops
				(best_length_ratio 0.2)
				(max_length 1)
				(best_width_ratio 0.9)
				(max_width 2)
				(curved_edges yes)
				(filter_ratio 0.9)
				(enabled yes)
				(allow_two_segments yes)
				(prefer_zone_connections yes)
			)
		)
		(pad "24" smd roundrect
			(at 2.475 0.598 270)
			(size 0.75 0.2)
			(layers "F.Cu" "F.Mask" "F.Paste")
			(roundrect_rratio 0.25)
			(net 604 "Net-(U37-~{OE2})")
			(pinfunction "~{OE2}")
			(pintype "input")
			(teardrops
				(best_length_ratio 0.2)
				(max_length 1)
				(best_width_ratio 0.9)
				(max_width 2)
				(curved_edges yes)
				(filter_ratio 0.9)
				(enabled yes)
				(allow_two_segments yes)
				(prefer_zone_connections yes)
			)
		)
		(pad "25" smd roundrect
			(at 2.475 0.2 270)
			(size 0.75 0.2)
			(layers "F.Cu" "F.Mask" "F.Paste")
			(roundrect_rratio 0.25)
			(net 2 "+3V3")
			(pinfunction "VDDA3V3")
			(pintype "power_in")
			(teardrops
				(best_length_ratio 0.2)
				(max_length 1)
				(best_width_ratio 0.9)
				(max_width 2)
				(curved_edges yes)
				(filter_ratio 0.9)
				(enabled yes)
				(allow_two_segments yes)
				(prefer_zone_connections yes)
			)
		)
		(pad "26" smd roundrect
			(at 2.475 -0.202 270)
			(size 0.75 0.2)
			(layers "F.Cu" "F.Mask" "F.Paste")
			(roundrect_rratio 0.25)
			(net 2 "+3V3")
			(pinfunction "VDDIO")
			(pintype "passive")
			(teardrops
				(best_length_ratio 0.2)
				(max_length 1)
				(best_width_ratio 0.9)
				(max_width 2)
				(curved_edges yes)
				(filter_ratio 0.9)
				(enabled yes)
				(allow_two_segments yes)
				(prefer_zone_connections yes)
			)
		)
		(pad "27" smd roundrect
			(at 2.475 -0.6 270)
			(size 0.75 0.2)
			(layers "F.Cu" "F.Mask" "F.Paste")
			(roundrect_rratio 0.25)
			(net 617 "/PCIe misc/DIF3+")
			(pinfunction "DIF3+")
			(pintype "output")
			(teardrops
				(best_length_ratio 0.2)
				(max_length 1)
				(best_width_ratio 0.9)
				(max_width 2)
				(curved_edges yes)
				(filter_ratio 0.9)
				(enabled yes)
				(allow_two_segments yes)
				(prefer_zone_connections yes)
			)
		)
		(pad "28" smd roundrect
			(at 2.475 -1 270)
			(size 0.75 0.2)
			(layers "F.Cu" "F.Mask" "F.Paste")
			(roundrect_rratio 0.25)
			(net 618 "/PCIe misc/DIF3-")
			(pinfunction "DIF3-")
			(pintype "output")
			(teardrops
				(best_length_ratio 0.2)
				(max_length 1)
				(best_width_ratio 0.9)
				(max_width 2)
				(curved_edges yes)
				(filter_ratio 0.9)
				(enabled yes)
				(allow_two_segments yes)
				(prefer_zone_connections yes)
			)
		)
		(pad "29" smd roundrect
			(at 2.475 -1.401 270)
			(size 0.75 0.2)
			(layers "F.Cu" "F.Mask" "F.Paste")
			(roundrect_rratio 0.25)
			(net 605 "Net-(U37-~{OE3})")
			(pinfunction "~{OE3}")
			(pintype "input")
			(teardrops
				(best_length_ratio 0.2)
				(max_length 1)
				(best_width_ratio 0.9)
				(max_width 2)
				(curved_edges yes)
				(filter_ratio 0.9)
				(enabled yes)
				(allow_two_segments yes)
				(prefer_zone_connections yes)
			)
		)
		(pad "30" smd roundrect
			(at 2.475 -1.801 270)
			(size 0.75 0.2)
			(layers "F.Cu" "F.Mask" "F.Paste")
			(roundrect_rratio 0.25)
			(net 789 "unconnected-(U37-NC-Pad30)")
			(pinfunction "NC")
			(pintype "no_connect")
			(teardrops
				(best_length_ratio 0.2)
				(max_length 1)
				(best_width_ratio 0.9)
				(max_width 2)
				(curved_edges yes)
				(filter_ratio 0.9)
				(enabled yes)
				(allow_two_segments yes)
				(prefer_zone_connections yes)
			)
		)
		(pad "31" smd roundrect
			(at 1.8 -2.476 270)
			(size 0.2 0.75)
			(layers "F.Cu" "F.Mask" "F.Paste")
			(roundrect_rratio 0.25)
			(net 2 "+3V3")
			(pinfunction "VDD3V3")
			(pintype "passive")
			(teardrops
				(best_length_ratio 0.2)
				(max_length 1)
				(best_width_ratio 0.9)
				(max_width 2)
				(curved_edges yes)
				(filter_ratio 0.9)
				(enabled yes)
				(allow_two_segments yes)
				(prefer_zone_connections yes)
			)
		)
		(pad "32" smd roundrect
			(at 1.398 -2.476 270)
			(size 0.2 0.75)
			(layers "F.Cu" "F.Mask" "F.Paste")
			(roundrect_rratio 0.25)
			(net 2 "+3V3")
			(pinfunction "VDDIO")
			(pintype "passive")
			(teardrops
				(best_length_ratio 0.2)
				(max_length 1)
				(best_width_ratio 0.9)
				(max_width 2)
				(curved_edges yes)
				(filter_ratio 0.9)
				(enabled yes)
				(allow_two_segments yes)
				(prefer_zone_connections yes)
			)
		)
	)
)
